(kicad_pcb
	(version 20260206)
	(generator "pcbnew")
	(generator_version "10.0")
	(general
		(thickness 1.6)
		(legacy_teardrops no)
	)
	(paper "A4")
	(title_block
		(title "04192023_DAF0TMB3IC0_F0TG_MB_C_brd_V02_OCP.brd")
		(comment 1 "Grand Teton / footprints 1239-1244 of 8354")
	)
	(layers
		(0 "F.Cu" signal "TOP")
		(4 "In1.Cu" signal "GND")
		(6 "In2.Cu" signal "IN1")
		(8 "In3.Cu" signal "GND1")
		(10 "In4.Cu" signal "IN2")
		(12 "In5.Cu" signal "GND2")
		(14 "In6.Cu" signal "IN3")
		(16 "In7.Cu" signal "GND3")
		(18 "In8.Cu" signal "VCC")
		(20 "In9.Cu" signal "VCC1")
		(22 "In10.Cu" signal "GND4")
		(24 "In11.Cu" signal "IN4")
		(26 "In12.Cu" signal "GND5")
		(28 "In13.Cu" signal "IN5")
		(30 "In14.Cu" signal "GND6")
		(32 "In15.Cu" signal "IN6")
		(34 "In16.Cu" signal "GND7")
		(2 "B.Cu" signal "BOTTOM")
		(9 "F.Adhes" user "F.Adhesive")
		(11 "B.Adhes" user "B.Adhesive")
		(13 "F.Paste" user "Package Geometry/Pastemask Top")
		(15 "B.Paste" user "Package Geometry/Pastemask Bottom")
		(5 "F.SilkS" user "Ref Des/Silkscreen Top")
		(7 "B.SilkS" user "Ref Des/Silkscreen Bottom")
		(1 "F.Mask" user "Board Geometry/Soldermask Top")
		(3 "B.Mask" user "Board Geometry/Soldermask Bottom")
		(17 "Dwgs.User" user "User.Drawings")
		(19 "Cmts.User" user "User.Comments")
		(21 "Eco1.User" user "User.Eco1")
		(23 "Eco2.User" user "User.Eco2")
		(25 "Edge.Cuts" user "Board Geometry/Outline")
		(27 "Margin" user)
		(31 "F.CrtYd" user "Package Geometry/Place Bound Top")
		(29 "B.CrtYd" user "Package Geometry/Place Bound Bottom")
		(35 "F.Fab" user "Ref Des/Assembly Top")
		(33 "B.Fab" user "Ref Des/Assembly Bottom")
	)
	(footprint ""
		(layer "F.Cu")
		(at 216.99855 -127.801116)
		(property "Reference" "R6825"
			(at 0 0 0)
			(layer "F.SilkS")
			(hide yes)
			(effects
				(font
					(size 1.27 1.27)
				)
			)
		)
		(property "Value" ""
			(at 0 0 0)
			(layer "F.Fab")
			(effects
				(font
					(size 1.27 1.27)
				)
			)
		)
		(duplicate_pad_numbers_are_jumpers no)
		(fp_line
			(start -0.7874 -0.4064)
			(end 0.7874 -0.4064)
			(stroke
				(width 0.1524)
				(type default)
			)
			(layer "F.SilkS")
		)
		(fp_line
			(start -0.7874 0.4064)
			(end -0.7874 -0.4064)
			(stroke
				(width 0.1524)
				(type default)
			)
			(layer "F.SilkS")
		)
		(fp_line
			(start 0.7874 -0.4064)
			(end 0.7874 0.4064)
			(stroke
				(width 0.1524)
				(type default)
			)
			(layer "F.SilkS")
		)
		(fp_line
			(start 0.7874 0.4064)
			(end -0.7874 0.4064)
			(stroke
				(width 0.1524)
				(type default)
			)
			(layer "F.SilkS")
		)
		(fp_line
			(start -0.67945 -0.305054)
			(end -0.12065 -0.305054)
			(stroke
				(width 0.1)
				(type default)
			)
			(layer "F.Fab")
		)
		(fp_line
			(start -0.67945 0.3048)
			(end -0.67945 -0.305054)
			(stroke
				(width 0.1)
				(type default)
			)
			(layer "F.Fab")
		)
		(fp_line
			(start -0.12065 -0.305054)
			(end -0.12065 -0.2794)
			(stroke
				(width 0.1)
				(type default)
			)
			(layer "F.Fab")
		)
		(fp_line
			(start -0.12065 -0.2794)
			(end 0.12065 -0.2794)
			(stroke
				(width 0.1)
				(type default)
			)
			(layer "F.Fab")
		)
		(fp_line
			(start -0.12065 0.2794)
			(end -0.12065 0.3048)
			(stroke
				(width 0.1)
				(type default)
			)
			(layer "F.Fab")
		)
		(fp_line
			(start -0.12065 0.3048)
			(end -0.67945 0.3048)
			(stroke
				(width 0.1)
				(type default)
			)
			(layer "F.Fab")
		)
		(fp_line
			(start 0.120396 0.2794)
			(end -0.12065 0.2794)
			(stroke
				(width 0.1)
				(type default)
			)
			(layer "F.Fab")
		)
		(fp_line
			(start 0.120396 0.3048)
			(end 0.120396 0.2794)
			(stroke
				(width 0.1)
				(type default)
			)
			(layer "F.Fab")
		)
		(fp_line
			(start 0.12065 -0.3048)
			(end 0.67945 -0.3048)
			(stroke
				(width 0.1)
				(type default)
			)
			(layer "F.Fab")
		)
		(fp_line
			(start 0.12065 -0.2794)
			(end 0.12065 -0.3048)
			(stroke
				(width 0.1)
				(type default)
			)
			(layer "F.Fab")
		)
		(fp_line
			(start 0.67945 -0.3048)
			(end 0.67945 0.3048)
			(stroke
				(width 0.1)
				(type default)
			)
			(layer "F.Fab")
		)
		(fp_line
			(start 0.67945 0.3048)
			(end 0.120396 0.3048)
			(stroke
				(width 0.1)
				(type default)
			)
			(layer "F.Fab")
		)
		(pad "1" smd circle
			(at -0.40005 0)
			(size 0 0)
			(layers "F.Cu" "F.Mask" "F.Paste")
			(net "RST_RT_CPU0_P3_PERST_R2_N")
		)
		(pad "2" smd circle
			(at 0.40005 0)
			(size 0 0)
			(layers "F.Cu" "F.Mask" "F.Paste")
			(net "RST_RT_CPU0_P3_PERST_R_N")
		)
	)
	(footprint ""
		(layer "F.Cu")
		(at 446.522602 -418.96411 -90)
		(property "Reference" "PR6613"
			(at 0 0 270)
			(layer "F.SilkS")
			(hide yes)
			(effects
				(font
					(size 1.27 1.27)
				)
			)
		)
		(property "Value" ""
			(at 0 0 270)
			(layer "F.Fab")
			(effects
				(font
					(size 1.27 1.27)
				)
			)
		)
		(duplicate_pad_numbers_are_jumpers no)
		(fp_line
			(start -0.7874 0.4064)
			(end -0.7874 -0.4064)
			(stroke
				(width 0.1524)
				(type default)
			)
			(layer "F.SilkS")
		)
		(fp_line
			(start 0.7874 0.4064)
			(end -0.7874 0.4064)
			(stroke
				(width 0.1524)
				(type default)
			)
			(layer "F.SilkS")
		)
		(fp_line
			(start -0.7874 -0.4064)
			(end 0.7874 -0.4064)
			(stroke
				(width 0.1524)
				(type default)
			)
			(layer "F.SilkS")
		)
		(fp_line
			(start 0.7874 -0.4064)
			(end 0.7874 0.4064)
			(stroke
				(width 0.1524)
				(type default)
			)
			(layer "F.SilkS")
		)
		(fp_line
			(start -0.67945 0.3048)
			(end -0.67945 -0.305054)
			(stroke
				(width 0.1)
				(type default)
			)
			(layer "F.Fab")
		)
		(fp_line
			(start -0.12065 0.3048)
			(end -0.67945 0.3048)
			(stroke
				(width 0.1)
				(type default)
			)
			(layer "F.Fab")
		)
		(fp_line
			(start 0.120396 0.3048)
			(end 0.120396 0.2794)
			(stroke
				(width 0.1)
				(type default)
			)
			(layer "F.Fab")
		)
		(fp_line
			(start 0.67945 0.3048)
			(end 0.120396 0.3048)
			(stroke
				(width 0.1)
				(type default)
			)
			(layer "F.Fab")
		)
		(fp_line
			(start -0.12065 0.2794)
			(end -0.12065 0.3048)
			(stroke
				(width 0.1)
				(type default)
			)
			(layer "F.Fab")
		)
		(fp_line
			(start 0.120396 0.2794)
			(end -0.12065 0.2794)
			(stroke
				(width 0.1)
				(type default)
			)
			(layer "F.Fab")
		)
		(fp_line
			(start -0.12065 -0.2794)
			(end 0.12065 -0.2794)
			(stroke
				(width 0.1)
				(type default)
			)
			(layer "F.Fab")
		)
		(fp_line
			(start 0.12065 -0.2794)
			(end 0.12065 -0.3048)
			(stroke
				(width 0.1)
				(type default)
			)
			(layer "F.Fab")
		)
		(fp_line
			(start 0.12065 -0.3048)
			(end 0.67945 -0.3048)
			(stroke
				(width 0.1)
				(type default)
			)
			(layer "F.Fab")
		)
		(fp_line
			(start 0.67945 -0.3048)
			(end 0.67945 0.3048)
			(stroke
				(width 0.1)
				(type default)
			)
			(layer "F.Fab")
		)
		(fp_line
			(start -0.67945 -0.305054)
			(end -0.12065 -0.305054)
			(stroke
				(width 0.1)
				(type default)
			)
			(layer "F.Fab")
		)
		(fp_line
			(start -0.12065 -0.305054)
			(end -0.12065 -0.2794)
			(stroke
				(width 0.1)
				(type default)
			)
			(layer "F.Fab")
		)
		(pad "1" smd circle
			(at -0.40005 0 270)
			(size 0 0)
			(layers "F.Cu" "F.Mask" "F.Paste")
			(net "NC_P0V9_RETIMER_CPU0_IMON7")
		)
		(pad "2" smd circle
			(at 0.40005 0 270)
			(size 0 0)
			(layers "F.Cu" "F.Mask" "F.Paste")
			(net "GND")
		)
	)
	(footprint ""
		(layer "F.Cu")
		(at 191.389 -50.673 90)
		(property "Reference" "D8002"
			(at -2.191004 -3.142488 90)
			(unlocked yes)
			(layer "F.SilkS")
			(effects
				(font
					(size 0.7874 0.5842)
					(thickness 0.1524)
				)
				(justify left)
			)
		)
		(property "Value" ""
			(at 0 0 90)
			(layer "F.Fab")
			(effects
				(font
					(size 1.27 1.27)
				)
			)
		)
		(duplicate_pad_numbers_are_jumpers no)
		(fp_line
			(start 1.778 -0.5588)
			(end 1.3208 -0.5588)
			(stroke
				(width 0.1524)
				(type default)
			)
			(layer "F.SilkS")
		)
		(fp_line
			(start 1.778 -0.5588)
			(end 1.778 0.5588)
			(stroke
				(width 0.1524)
				(type default)
			)
			(layer "F.SilkS")
		)
		(fp_line
			(start 1.4732 -0.5588)
			(end 1.4732 0.5588)
			(stroke
				(width 0.1524)
				(type default)
			)
			(layer "F.SilkS")
		)
		(fp_line
			(start 1.3208 -0.5588)
			(end 1.3208 0.5588)
			(stroke
				(width 0.1524)
				(type default)
			)
			(layer "F.SilkS")
		)
		(fp_line
			(start -1.3208 -0.5588)
			(end 1.3208 -0.5588)
			(stroke
				(width 0.1524)
				(type default)
			)
			(layer "F.SilkS")
		)
		(fp_line
			(start 1.778 0.5588)
			(end 1.3208 0.5588)
			(stroke
				(width 0.1524)
				(type default)
			)
			(layer "F.SilkS")
		)
		(fp_line
			(start 1.6256 0.5588)
			(end 1.6256 -0.5588)
			(stroke
				(width 0.1524)
				(type default)
			)
			(layer "F.SilkS")
		)
		(fp_line
			(start 1.3208 0.5588)
			(end -1.3208 0.5588)
			(stroke
				(width 0.1524)
				(type default)
			)
			(layer "F.SilkS")
		)
		(fp_line
			(start -1.3208 0.5588)
			(end -1.3208 -0.5588)
			(stroke
				(width 0.1524)
				(type default)
			)
			(layer "F.SilkS")
		)
		(fp_line
			(start 0.899922 -0.40005)
			(end 0.899922 0.40005)
			(stroke
				(width 0.1)
				(type default)
			)
			(layer "F.Fab")
		)
		(fp_line
			(start -0.899922 -0.40005)
			(end 0.899922 -0.40005)
			(stroke
				(width 0.1)
				(type default)
			)
			(layer "F.Fab")
		)
		(fp_line
			(start 0.899922 0.40005)
			(end -0.899922 0.40005)
			(stroke
				(width 0.1)
				(type default)
			)
			(layer "F.Fab")
		)
		(fp_line
			(start -0.899922 0.40005)
			(end -0.899922 -0.40005)
			(stroke
				(width 0.1)
				(type default)
			)
			(layer "F.Fab")
		)
		(fp_text user "+"
			(at -2.6162 -0.22225 90)
			(unlocked yes)
			(layer "F.SilkS")
			(effects
				(font
					(size 1.905 1.4224)
					(thickness 0.1524)
				)
				(justify left)
			)
		)
		(fp_text user "-"
			(at 1.73101 0.59436 90)
			(unlocked yes)
			(layer "F.SilkS")
			(effects
				(font
					(size 1.905 1.4224)
					(thickness 0.1524)
				)
				(justify left)
			)
		)
		(fp_text user "-"
			(at 1.651 -0.22225 90)
			(unlocked yes)
			(layer "F.Fab")
			(effects
				(font
					(size 1.905 1.4224)
					(thickness 0.1524)
				)
				(justify left)
			)
		)
		(fp_text user "+"
			(at -2.6162 -0.22225 90)
			(unlocked yes)
			(layer "F.Fab")
			(effects
				(font
					(size 1.905 1.4224)
					(thickness 0.1524)
				)
				(justify left)
			)
		)
		(pad "A" smd rect
			(at -0.750062 0 90)
			(size 0.8128 0.8128)
			(layers "F.Cu" "F.Mask" "F.Paste")
			(net "LED_P12V_SCM_FAULT")
		)
		(pad "C" smd rect
			(at 0.750062 0 90)
			(size 0.8128 0.8128)
			(layers "F.Cu" "F.Mask" "F.Paste")
			(net "LED_P12V_SCM_FAULT_D2")
		)
	)
	(footprint ""
		(layer "F.Cu")
		(at 178.71694 -402.468842 180)
		(property "Reference" "PC2187"
			(at 0 0 180)
			(layer "F.SilkS")
			(hide yes)
			(effects
				(font
					(size 1.27 1.27)
				)
			)
		)
		(property "Value" ""
			(at 0 0 180)
			(layer "F.Fab")
			(effects
				(font
					(size 1.27 1.27)
				)
			)
		)
		(duplicate_pad_numbers_are_jumpers no)
		(fp_line
			(start 0.7874 0.4064)
			(end -0.7874 0.4064)
			(stroke
				(width 0.1524)
				(type default)
			)
			(layer "F.SilkS")
		)
		(fp_line
			(start 0.7874 -0.4064)
			(end 0.7874 0.4064)
			(stroke
				(width 0.1524)
				(type default)
			)
			(layer "F.SilkS")
		)
		(fp_line
			(start -0.7874 0.4064)
			(end -0.7874 -0.4064)
			(stroke
				(width 0.1524)
				(type default)
			)
			(layer "F.SilkS")
		)
		(fp_line
			(start -0.7874 -0.4064)
			(end 0.7874 -0.4064)
			(stroke
				(width 0.1524)
				(type default)
			)
			(layer "F.SilkS")
		)
		(fp_line
			(start 0.67945 0.3048)
			(end 0.120396 0.3048)
			(stroke
				(width 0.1)
				(type default)
			)
			(layer "F.Fab")
		)
		(fp_line
			(start 0.67945 -0.3048)
			(end 0.67945 0.3048)
			(stroke
				(width 0.1)
				(type default)
			)
			(layer "F.Fab")
		)
		(fp_line
			(start 0.12065 -0.2794)
			(end 0.12065 -0.3048)
			(stroke
				(width 0.1)
				(type default)
			)
			(layer "F.Fab")
		)
		(fp_line
			(start 0.12065 -0.3048)
			(end 0.67945 -0.3048)
			(stroke
				(width 0.1)
				(type default)
			)
			(layer "F.Fab")
		)
		(fp_line
			(start 0.120396 0.3048)
			(end 0.120396 0.2794)
			(stroke
				(width 0.1)
				(type default)
			)
			(layer "F.Fab")
		)
		(fp_line
			(start 0.120396 0.2794)
			(end -0.12065 0.2794)
			(stroke
				(width 0.1)
				(type default)
			)
			(layer "F.Fab")
		)
		(fp_line
			(start -0.12065 0.3048)
			(end -0.67945 0.3048)
			(stroke
				(width 0.1)
				(type default)
			)
			(layer "F.Fab")
		)
		(fp_line
			(start -0.12065 0.2794)
			(end -0.12065 0.3048)
			(stroke
				(width 0.1)
				(type default)
			)
			(layer "F.Fab")
		)
		(fp_line
			(start -0.12065 -0.2794)
			(end 0.12065 -0.2794)
			(stroke
				(width 0.1)
				(type default)
			)
			(layer "F.Fab")
		)
		(fp_line
			(start -0.12065 -0.305054)
			(end -0.12065 -0.2794)
			(stroke
				(width 0.1)
				(type default)
			)
			(layer "F.Fab")
		)
		(fp_line
			(start -0.67945 0.3048)
			(end -0.67945 -0.305054)
			(stroke
				(width 0.1)
				(type default)
			)
			(layer "F.Fab")
		)
		(fp_line
			(start -0.67945 -0.305054)
			(end -0.12065 -0.305054)
			(stroke
				(width 0.1)
				(type default)
			)
			(layer "F.Fab")
		)
		(pad "1" smd circle
			(at -0.40005 0 180)
			(size 0 0)
			(layers "F.Cu" "F.Mask" "F.Paste")
			(net "HSC_VDD_R")
		)
		(pad "2" smd circle
			(at 0.40005 0 180)
			(size 0 0)
			(layers "F.Cu" "F.Mask" "F.Paste")
			(net "AGND_HSC")
		)
	)
	(footprint ""
		(layer "F.Cu")
		(at 42.637964 -173.938946 180)
		(property "Reference" "R5019"
			(at 0 0 180)
			(layer "F.SilkS")
			(hide yes)
			(effects
				(font
					(size 1.27 1.27)
				)
			)
		)
		(property "Value" ""
			(at 0 0 180)
			(layer "F.Fab")
			(effects
				(font
					(size 1.27 1.27)
				)
			)
		)
		(duplicate_pad_numbers_are_jumpers no)
		(fp_line
			(start 0.7874 0.4064)
			(end -0.7874 0.4064)
			(stroke
				(width 0.1524)
				(type default)
			)
			(layer "F.SilkS")
		)
		(fp_line
			(start 0.7874 -0.4064)
			(end 0.7874 0.4064)
			(stroke
				(width 0.1524)
				(type default)
			)
			(layer "F.SilkS")
		)
		(fp_line
			(start -0.7874 0.4064)
			(end -0.7874 -0.4064)
			(stroke
				(width 0.1524)
				(type default)
			)
			(layer "F.SilkS")
		)
		(fp_line
			(start -0.7874 -0.4064)
			(end 0.7874 -0.4064)
			(stroke
				(width 0.1524)
				(type default)
			)
			(layer "F.SilkS")
		)
		(fp_line
			(start 0.67945 0.3048)
			(end 0.120396 0.3048)
			(stroke
				(width 0.1)
				(type default)
			)
			(layer "F.Fab")
		)
		(fp_line
			(start 0.67945 -0.3048)
			(end 0.67945 0.3048)
			(stroke
				(width 0.1)
				(type default)
			)
			(layer "F.Fab")
		)
		(fp_line
			(start 0.12065 -0.2794)
			(end 0.12065 -0.3048)
			(stroke
				(width 0.1)
				(type default)
			)
			(layer "F.Fab")
		)
		(fp_line
			(start 0.12065 -0.3048)
			(end 0.67945 -0.3048)
			(stroke
				(width 0.1)
				(type default)
			)
			(layer "F.Fab")
		)
		(fp_line
			(start 0.120396 0.3048)
			(end 0.120396 0.2794)
			(stroke
				(width 0.1)
				(type default)
			)
			(layer "F.Fab")
		)
		(fp_line
			(start 0.120396 0.2794)
			(end -0.12065 0.2794)
			(stroke
				(width 0.1)
				(type default)
			)
			(layer "F.Fab")
		)
		(fp_line
			(start -0.12065 0.3048)
			(end -0.67945 0.3048)
			(stroke
				(width 0.1)
				(type default)
			)
			(layer "F.Fab")
		)
		(fp_line
			(start -0.12065 0.2794)
			(end -0.12065 0.3048)
			(stroke
				(width 0.1)
				(type default)
			)
			(layer "F.Fab")
		)
		(fp_line
			(start -0.12065 -0.2794)
			(end 0.12065 -0.2794)
			(stroke
				(width 0.1)
				(type default)
			)
			(layer "F.Fab")
		)
		(fp_line
			(start -0.12065 -0.305054)
			(end -0.12065 -0.2794)
			(stroke
				(width 0.1)
				(type default)
			)
			(layer "F.Fab")
		)
		(fp_line
			(start -0.67945 0.3048)
			(end -0.67945 -0.305054)
			(stroke
				(width 0.1)
				(type default)
			)
			(layer "F.Fab")
		)
		(fp_line
			(start -0.67945 -0.305054)
			(end -0.12065 -0.305054)
			(stroke
				(width 0.1)
				(type default)
			)
			(layer "F.Fab")
		)
		(pad "1" smd circle
			(at -0.40005 0 180)
			(size 0 0)
			(layers "F.Cu" "F.Mask" "F.Paste")
			(net "PVDD11_S3_P1")
		)
		(pad "2" smd circle
			(at 0.40005 0 180)
			(size 0 0)
			(layers "F.Cu" "F.Mask" "F.Paste")
			(net "I3C_SCM_2_R_SDA")
		)
	)
	(footprint ""
		(layer "F.Cu")
		(at 215.519 -119.888 90)
		(property "Reference" "U9001"
			(at -1.901444 4.060952 90)
			(unlocked yes)
			(layer "F.SilkS")
			(effects
				(font
					(size 0.7874 0.5842)
					(thickness 0.1524)
				)
				(justify left)
			)
		)
		(property "Value" ""
			(at 0 0 90)
			(layer "F.Fab")
			(effects
				(font
					(size 1.27 1.27)
				)
			)
		)
		(duplicate_pad_numbers_are_jumpers no)
		(fp_line
			(start 1.733296 -1.549908)
			(end 0.660908 -1.549908)
			(stroke
				(width 0.1524)
				(type default)
			)
			(layer "F.SilkS")
		)
		(fp_line
			(start 0.660908 -1.549908)
			(end 0 -0.889)
			(stroke
				(width 0.1524)
				(type default)
			)
			(layer "F.SilkS")
		)
		(fp_line
			(start -0.660908 -1.549908)
			(end -1.733296 -1.549908)
			(stroke
				(width 0.1524)
				(type default)
			)
			(layer "F.SilkS")
		)
		(fp_line
			(start -1.733296 -1.549908)
			(end -1.733296 1.549908)
			(stroke
				(width 0.1524)
				(type default)
			)
			(layer "F.SilkS")
		)
		(fp_line
			(start 0 -0.889)
			(end -0.660908 -1.549908)
			(stroke
				(width 0.1524)
				(type default)
			)
			(layer "F.SilkS")
		)
		(fp_line
			(start 1.733296 1.549908)
			(end 1.733296 -1.549908)
			(stroke
				(width 0.1524)
				(type default)
			)
			(layer "F.SilkS")
		)
		(fp_line
			(start -1.733296 1.549908)
			(end 1.733296 1.549908)
			(stroke
				(width 0.1524)
				(type default)
			)
			(layer "F.SilkS")
		)
		(fp_poly
			(pts
				(xy -2.4384 -1.20396) (xy -2.4384 -0.69596) (xy -1.9304 -0.94996)
			)
			(stroke
				(width 0)
				(type default)
			)
			(fill yes)
			(layer "F.SilkS")
		)
		(fp_line
			(start 0.849884 -1.549908)
			(end -0.849884 -1.549908)
			(stroke
				(width 0.1)
				(type default)
			)
			(layer "F.Fab")
		)
		(fp_line
			(start -0.849884 -1.549908)
			(end -0.849884 1.549908)
			(stroke
				(width 0.1)
				(type default)
			)
			(layer "F.Fab")
		)
		(fp_line
			(start 0.849884 1.549908)
			(end 0.849884 -1.549908)
			(stroke
				(width 0.1)
				(type default)
			)
			(layer "F.Fab")
		)
		(fp_line
			(start -0.849884 1.549908)
			(end 0.849884 1.549908)
			(stroke
				(width 0.1)
				(type default)
			)
			(layer "F.Fab")
		)
		(fp_poly
			(pts
				(xy -2.4384 -1.20396) (xy -2.4384 -0.69596) (xy -1.9304 -0.94996)
			)
			(stroke
				(width 0)
				(type default)
			)
			(fill yes)
			(layer "F.Fab")
		)
		(pad "1" smd rect
			(at -1.199896 -0.94996)
			(size 0.5588 0.8128)
			(layers "F.Cu" "F.Mask" "F.Paste")
			(net "RST_PERST_OCP_SFF_R_N")
		)
		(pad "2" smd rect
			(at -1.199896 0)
			(size 0.5588 0.8128)
			(layers "F.Cu" "F.Mask" "F.Paste")
			(net "HP_LVC3_OCP_V3_1_PWRGD")
		)
		(pad "3" smd rect
			(at -1.199896 0.94996)
			(size 0.5588 0.8128)
			(layers "F.Cu" "F.Mask" "F.Paste")
			(net "GND")
		)
		(pad "4" smd rect
			(at 1.199896 0.94996)
			(size 0.5588 0.8128)
			(layers "F.Cu" "F.Mask" "F.Paste")
			(net "RST_PERST_OCP_SFF_BUF_R_N")
		)
		(pad "5" smd rect
			(at 1.199896 -0.94996)
			(size 0.5588 0.8128)
			(layers "F.Cu" "F.Mask" "F.Paste")
			(net "P3V3_AUX")
		)
	)
)
